# S9S_MB_2U (Grand Teton) — schematic netlist excerpt (pin names and nets, part order shuffled) for the footprints in the layout excerpt that follows; sources: Cadence DE-HDL packaged netlist, KiCad conversion of 03242023_DA0F0TMBIJ0_F0T_Motherboard_J_brd_V01_OCP.brd

C975  Q_CAP  10UF 6.3V 20% X6S  pkg C0402  page 74 : A = PVCCIN_CPU0 ; B = GND
C1331  Q_CAP  10UF 16V 10% X6S  pkg C0805  page 260 : A = P5V ; B = GND
R109  Q_RES  33.2 1% CHIP  pkg 0402LF  page 223 : A = FM_PLD_CLK_25M_R_EN ; B = FM_PLD_CLK_25M_EN

(kicad_pcb
	(version 20260206)
	(generator "pcbnew")
	(generator_version "10.0")
	(general
		(thickness 1.6)
		(legacy_teardrops no)
	)
	(paper "A4")
	(title_block
		(title "03242023_DA0F0TMBIJ0_F0T_Motherboard_J_brd_V01_OCP.brd")
		(comment 1 "Grand Teton / footprints 1654-1656 of 6105")
	)
	(layers
		(0 "F.Cu" signal "TOP")
		(4 "In1.Cu" signal "GND")
		(6 "In2.Cu" signal "IN1")
		(8 "In3.Cu" signal "GND1")
		(10 "In4.Cu" signal "IN2")
		(12 "In5.Cu" signal "GND2")
		(14 "In6.Cu" signal "IN3")
		(16 "In7.Cu" signal "GND3")
		(18 "In8.Cu" signal "VCC")
		(20 "In9.Cu" signal "VCC1")
		(22 "In10.Cu" signal "GND4")
		(24 "In11.Cu" signal "IN4")
		(26 "In12.Cu" signal "GND5")
		(28 "In13.Cu" signal "IN5")
		(30 "In14.Cu" signal "GND6")
		(32 "In15.Cu" signal "IN6")
		(34 "In16.Cu" signal "GND7")
		(2 "B.Cu" signal "BOTTOM")
		(9 "F.Adhes" user "F.Adhesive")
		(11 "B.Adhes" user "B.Adhesive")
		(13 "F.Paste" user "Package Geometry/Pastemask Top")
		(15 "B.Paste" user "Package Geometry/Pastemask Bottom")
		(5 "F.SilkS" user "Ref Des/Silkscreen Top")
		(7 "B.SilkS" user "Ref Des/Silkscreen Bottom")
		(1 "F.Mask" user "Board Geometry/Soldermask Top")
		(3 "B.Mask" user "Board Geometry/Soldermask Bottom")
		(17 "Dwgs.User" user "User.Drawings")
		(19 "Cmts.User" user "User.Comments")
		(21 "Eco1.User" user "User.Eco1")
		(23 "Eco2.User" user "User.Eco2")
		(25 "Edge.Cuts" user "Board Geometry/Outline")
		(27 "Margin" user)
		(31 "F.CrtYd" user "Package Geometry/Place Bound Top")
		(29 "B.CrtYd" user "Package Geometry/Place Bound Bottom")
		(35 "F.Fab" user "Ref Des/Assembly Top")
		(33 "B.Fab" user "Ref Des/Assembly Bottom")
	)
	(footprint ""
		(layer "F.Cu")
		(at 354.282248 -247.715024 90)
		(property "Reference" "C975"
			(at 0 0 90)
			(layer "F.SilkS")
			(hide yes)
			(effects
				(font
					(size 1.27 1.27)
				)
			)
		)
		(property "Value" ""
			(at 0 0 90)
			(layer "F.Fab")
			(effects
				(font
					(size 1.27 1.27)
				)
			)
		)
		(duplicate_pad_numbers_are_jumpers no)
		(fp_line
			(start 0.7874 -0.4064)
			(end 0.7874 0.4064)
			(stroke
				(width 0.1524)
				(type default)
			)
			(layer "F.SilkS")
		)
		(fp_line
			(start -0.7874 -0.4064)
			(end 0.7874 -0.4064)
			(stroke
				(width 0.1524)
				(type default)
			)
			(layer "F.SilkS")
		)
		(fp_line
			(start 0.7874 0.4064)
			(end -0.7874 0.4064)
			(stroke
				(width 0.1524)
				(type default)
			)
			(layer "F.SilkS")
		)
		(fp_line
			(start -0.7874 0.4064)
			(end -0.7874 -0.4064)
			(stroke
				(width 0.1524)
				(type default)
			)
			(layer "F.SilkS")
		)
		(fp_line
			(start -0.12065 -0.305054)
			(end -0.12065 -0.2794)
			(stroke
				(width 0.1)
				(type default)
			)
			(layer "F.Fab")
		)
		(fp_line
			(start -0.67945 -0.305054)
			(end -0.12065 -0.305054)
			(stroke
				(width 0.1)
				(type default)
			)
			(layer "F.Fab")
		)
		(fp_line
			(start 0.67945 -0.3048)
			(end 0.67945 0.3048)
			(stroke
				(width 0.1)
				(type default)
			)
			(layer "F.Fab")
		)
		(fp_line
			(start 0.12065 -0.3048)
			(end 0.67945 -0.3048)
			(stroke
				(width 0.1)
				(type default)
			)
			(layer "F.Fab")
		)
		(fp_line
			(start 0.12065 -0.2794)
			(end 0.12065 -0.3048)
			(stroke
				(width 0.1)
				(type default)
			)
			(layer "F.Fab")
		)
		(fp_line
			(start -0.12065 -0.2794)
			(end 0.12065 -0.2794)
			(stroke
				(width 0.1)
				(type default)
			)
			(layer "F.Fab")
		)
		(fp_line
			(start 0.120396 0.2794)
			(end -0.12065 0.2794)
			(stroke
				(width 0.1)
				(type default)
			)
			(layer "F.Fab")
		)
		(fp_line
			(start -0.12065 0.2794)
			(end -0.12065 0.3048)
			(stroke
				(width 0.1)
				(type default)
			)
			(layer "F.Fab")
		)
		(fp_line
			(start 0.67945 0.3048)
			(end 0.120396 0.3048)
			(stroke
				(width 0.1)
				(type default)
			)
			(layer "F.Fab")
		)
		(fp_line
			(start 0.120396 0.3048)
			(end 0.120396 0.2794)
			(stroke
				(width 0.1)
				(type default)
			)
			(layer "F.Fab")
		)
		(fp_line
			(start -0.12065 0.3048)
			(end -0.67945 0.3048)
			(stroke
				(width 0.1)
				(type default)
			)
			(layer "F.Fab")
		)
		(fp_line
			(start -0.67945 0.3048)
			(end -0.67945 -0.305054)
			(stroke
				(width 0.1)
				(type default)
			)
			(layer "F.Fab")
		)
		(pad "1" smd circle
			(at -0.40005 0 90)
			(size 0 0)
			(layers "F.Cu" "F.Mask" "F.Paste")
			(net "PVCCIN_CPU0")
		)
		(pad "2" smd circle
			(at 0.40005 0 90)
			(size 0 0)
			(layers "F.Cu" "F.Mask" "F.Paste")
			(net "GND")
		)
	)
	(footprint ""
		(layer "F.Cu")
		(at 197.41388 -107.495848)
		(property "Reference" "R109"
			(at 0 0 0)
			(layer "F.SilkS")
			(hide yes)
			(effects
				(font
					(size 1.27 1.27)
				)
			)
		)
		(property "Value" ""
			(at 0 0 0)
			(layer "F.Fab")
			(effects
				(font
					(size 1.27 1.27)
				)
			)
		)
		(duplicate_pad_numbers_are_jumpers no)
		(fp_line
			(start -0.7874 -0.4064)
			(end 0.7874 -0.4064)
			(stroke
				(width 0.1524)
				(type default)
			)
			(layer "F.SilkS")
		)
		(fp_line
			(start -0.7874 0.4064)
			(end -0.7874 -0.4064)
			(stroke
				(width 0.1524)
				(type default)
			)
			(layer "F.SilkS")
		)
		(fp_line
			(start 0.7874 -0.4064)
			(end 0.7874 0.4064)
			(stroke
				(width 0.1524)
				(type default)
			)
			(layer "F.SilkS")
		)
		(fp_line
			(start 0.7874 0.4064)
			(end -0.7874 0.4064)
			(stroke
				(width 0.1524)
				(type default)
			)
			(layer "F.SilkS")
		)
		(fp_line
			(start -0.67945 -0.305054)
			(end -0.12065 -0.305054)
			(stroke
				(width 0.1)
				(type default)
			)
			(layer "F.Fab")
		)
		(fp_line
			(start -0.67945 0.3048)
			(end -0.67945 -0.305054)
			(stroke
				(width 0.1)
				(type default)
			)
			(layer "F.Fab")
		)
		(fp_line
			(start -0.12065 -0.305054)
			(end -0.12065 -0.2794)
			(stroke
				(width 0.1)
				(type default)
			)
			(layer "F.Fab")
		)
		(fp_line
			(start -0.12065 -0.2794)
			(end 0.12065 -0.2794)
			(stroke
				(width 0.1)
				(type default)
			)
			(layer "F.Fab")
		)
		(fp_line
			(start -0.12065 0.2794)
			(end -0.12065 0.3048)
			(stroke
				(width 0.1)
				(type default)
			)
			(layer "F.Fab")
		)
		(fp_line
			(start -0.12065 0.3048)
			(end -0.67945 0.3048)
			(stroke
				(width 0.1)
				(type default)
			)
			(layer "F.Fab")
		)
		(fp_line
			(start 0.120396 0.2794)
			(end -0.12065 0.2794)
			(stroke
				(width 0.1)
				(type default)
			)
			(layer "F.Fab")
		)
		(fp_line
			(start 0.120396 0.3048)
			(end 0.120396 0.2794)
			(stroke
				(width 0.1)
				(type default)
			)
			(layer "F.Fab")
		)
		(fp_line
			(start 0.12065 -0.3048)
			(end 0.67945 -0.3048)
			(stroke
				(width 0.1)
				(type default)
			)
			(layer "F.Fab")
		)
		(fp_line
			(start 0.12065 -0.2794)
			(end 0.12065 -0.3048)
			(stroke
				(width 0.1)
				(type default)
			)
			(layer "F.Fab")
		)
		(fp_line
			(start 0.67945 -0.3048)
			(end 0.67945 0.3048)
			(stroke
				(width 0.1)
				(type default)
			)
			(layer "F.Fab")
		)
		(fp_line
			(start 0.67945 0.3048)
			(end 0.120396 0.3048)
			(stroke
				(width 0.1)
				(type default)
			)
			(layer "F.Fab")
		)
		(pad "1" smd circle
			(at -0.40005 0)
			(size 0 0)
			(layers "F.Cu" "F.Mask" "F.Paste")
			(net "FM_PLD_CLK_25M_R_EN")
		)
		(pad "2" smd circle
			(at 0.40005 0)
			(size 0 0)
			(layers "F.Cu" "F.Mask" "F.Paste")
			(net "FM_PLD_CLK_25M_EN")
		)
	)
	(footprint ""
		(layer "F.Cu")
		(at 442.91123 -370.248434)
		(property "Reference" "C1331"
			(at 0 0 0)
			(layer "F.SilkS")
			(hide yes)
			(effects
				(font
					(size 1.27 1.27)
				)
			)
		)
		(property "Value" ""
			(at 0 0 0)
			(layer "F.Fab")
			(effects
				(font
					(size 1.27 1.27)
				)
			)
		)
		(duplicate_pad_numbers_are_jumpers no)
		(fp_line
			(start -1.524 -0.762)
			(end 1.524 -0.762)
			(stroke
				(width 0.1524)
				(type default)
			)
			(layer "F.SilkS")
		)
		(fp_line
			(start -1.524 0.762)
			(end -1.524 -0.762)
			(stroke
				(width 0.1524)
				(type default)
			)
			(layer "F.SilkS")
		)
		(fp_line
			(start 1.524 -0.762)
			(end 1.524 0.762)
			(stroke
				(width 0.1524)
				(type default)
			)
			(layer "F.SilkS")
		)
		(fp_line
			(start 1.524 0.762)
			(end -1.524 0.762)
			(stroke
				(width 0.1524)
				(type default)
			)
			(layer "F.SilkS")
		)
		(fp_line
			(start -1.1049 -0.724916)
			(end -1.1049 0.724916)
			(stroke
				(width 0.1)
				(type default)
			)
			(layer "F.Fab")
		)
		(fp_line
			(start -1.1049 0.724916)
			(end 1.1049 0.724916)
			(stroke
				(width 0.1)
				(type default)
			)
			(layer "F.Fab")
		)
		(fp_line
			(start 1.1049 -0.724916)
			(end -1.1049 -0.724916)
			(stroke
				(width 0.1)
				(type default)
			)
			(layer "F.Fab")
		)
		(fp_line
			(start 1.1049 0.724916)
			(end 1.1049 -0.724916)
			(stroke
				(width 0.1)
				(type default)
			)
			(layer "F.Fab")
		)
		(pad "1" smd rect
			(at -0.889 0 180)
			(size 1.016 1.27)
			(layers "F.Cu" "F.Mask" "F.Paste")
			(net "P5V")
		)
		(pad "2" smd rect
			(at 0.889 0 180)
			(size 1.016 1.27)
			(layers "F.Cu" "F.Mask" "F.Paste")
			(net "GND")
		)
	)
)
